(kicad_pcb
	(version 20260206)
	(generator "pcbnew")
	(generator_version "10.0")
	(general
		(thickness 1.6)
		(legacy_teardrops no)
	)
	(paper "A4")
	(title_block
		(title "Wiwynn_Tioga_Pass_MB.brd")
		(comment 1 "Tioga Pass / footprint 2031 of 4770 (J1A2), pads 1-123 of 291")
	)
	(layers
		(0 "F.Cu" signal "TOP")
		(4 "In1.Cu" signal "L2GND")
		(6 "In2.Cu" signal "L3")
		(8 "In3.Cu" signal "L4GND")
		(10 "In4.Cu" signal "L5")
		(12 "In5.Cu" signal "L6GND")
		(14 "In6.Cu" signal "L7VCC")
		(16 "In7.Cu" signal "L8VCC")
		(18 "In8.Cu" signal "L9GND")
		(20 "In9.Cu" signal "L10")
		(22 "In10.Cu" signal "L11GND")
		(24 "In11.Cu" signal "L12")
		(26 "In12.Cu" signal "L13GND")
		(2 "B.Cu" signal "BOTTOM")
		(9 "F.Adhes" user "F.Adhesive")
		(11 "B.Adhes" user "B.Adhesive")
		(13 "F.Paste" user "Package Geometry/Pastemask Top")
		(15 "B.Paste" user "Package Geometry/Pastemask Bottom")
		(5 "F.SilkS" user "Ref Des/Silkscreen Top")
		(7 "B.SilkS" user "Ref Des/Silkscreen Bottom")
		(1 "F.Mask" user "Board Geometry/Soldermask Top")
		(3 "B.Mask" user "Board Geometry/Soldermask Bottom")
		(17 "Dwgs.User" user "User.Drawings")
		(19 "Cmts.User" user "User.Comments")
		(21 "Eco1.User" user "User.Eco1")
		(23 "Eco2.User" user "User.Eco2")
		(25 "Edge.Cuts" user "Board Geometry/Outline")
		(27 "Margin" user)
		(31 "F.CrtYd" user "Package Geometry/Place Bound Top")
		(29 "B.CrtYd" user "Package Geometry/Place Bound Bottom")
		(35 "F.Fab" user "Ref Des/Assembly Top")
		(33 "B.Fab" user "Ref Des/Assembly Bottom")
	)
	(footprint ""
		(layer "F.Cu")
		(at 29.699458 -142.6718 90)
		(property "Reference" "J1A2"
			(at -2.623312 42.436542 0)
			(unlocked yes)
			(layer "F.SilkS")
			(effects
				(font
					(size 0.7874 0.5842)
					(thickness 0.1524)
				)
				(justify left)
			)
		)
		(property "Value" ""
			(at 0 0 90)
			(layer "F.Fab")
			(effects
				(font
					(size 1.27 1.27)
				)
			)
		)
		(duplicate_pad_numbers_are_jumpers no)
		(pad "" thru_hole circle
			(at 2.29997 -5.649976 90)
			(size 2.8194 2.8194)
			(drill 2.4384)
			(layers "*.Cu" "*.Mask")
			(remove_unused_layers no)
			(clearance 0.127)
			(thermal_gap 0.127)
		)
		(pad "" thru_hole oval
			(at 2.29997 68.90004 90)
			(size 2.8194 1.5748)
			(drill oval 2.4384 1.1938)
			(layers "*.Cu" "*.Mask")
			(remove_unused_layers no)
			(clearance 0.127)
			(thermal_gap 0.127)
		)
		(pad "" thru_hole circle
			(at 2.29997 132.299964 90)
			(size 2.8194 2.8194)
			(drill 2.4384)
			(layers "*.Cu" "*.Mask")
			(remove_unused_layers no)
			(clearance 0.127)
			(thermal_gap 0.127)
		)
		(pad "1" smd rect
			(at 0 0 90)
			(size 1.8034 0.508)
			(layers "F.Cu" "F.Mask" "F.Paste")
			(net "P12V_NVDIMM_KLM")
		)
		(pad "2" smd rect
			(at 0 0.849884 90)
			(size 1.8034 0.508)
			(layers "F.Cu" "F.Mask" "F.Paste")
			(net "GND")
		)
		(pad "3" smd rect
			(at 0 1.700022 90)
			(size 1.8034 0.508)
			(layers "F.Cu" "F.Mask" "F.Paste")
			(net "M_L_DQ<5>")
		)
		(pad "4" smd rect
			(at 0 2.549906 90)
			(size 1.8034 0.508)
			(layers "F.Cu" "F.Mask" "F.Paste")
			(net "GND")
		)
		(pad "5" smd rect
			(at 0 3.400044 90)
			(size 1.8034 0.508)
			(layers "F.Cu" "F.Mask" "F.Paste")
			(net "M_L_DQ<1>")
		)
		(pad "6" smd rect
			(at 0 4.249928 90)
			(size 1.8034 0.508)
			(layers "F.Cu" "F.Mask" "F.Paste")
			(net "GND")
		)
		(pad "7" smd rect
			(at 0 5.100066 90)
			(size 1.8034 0.508)
			(layers "F.Cu" "F.Mask" "F.Paste")
			(net "M_L_DQS_DP<9>")
		)
		(pad "8" smd rect
			(at 0 5.94995 90)
			(size 1.8034 0.508)
			(layers "F.Cu" "F.Mask" "F.Paste")
			(net "M_L_DQS_DN<9>")
		)
		(pad "9" smd rect
			(at 0 6.800088 90)
			(size 1.8034 0.508)
			(layers "F.Cu" "F.Mask" "F.Paste")
			(net "GND")
		)
		(pad "10" smd rect
			(at 0 7.649972 90)
			(size 1.8034 0.508)
			(layers "F.Cu" "F.Mask" "F.Paste")
			(net "M_L_DQ<7>")
		)
		(pad "11" smd rect
			(at 0 8.50011 90)
			(size 1.8034 0.508)
			(layers "F.Cu" "F.Mask" "F.Paste")
			(net "GND")
		)
		(pad "12" smd rect
			(at 0 9.349994 90)
			(size 1.8034 0.508)
			(layers "F.Cu" "F.Mask" "F.Paste")
			(net "M_L_DQ<3>")
		)
		(pad "13" smd rect
			(at 0 10.199878 90)
			(size 1.8034 0.508)
			(layers "F.Cu" "F.Mask" "F.Paste")
			(net "GND")
		)
		(pad "14" smd rect
			(at 0 11.050016 90)
			(size 1.8034 0.508)
			(layers "F.Cu" "F.Mask" "F.Paste")
			(net "M_L_DQ<13>")
		)
		(pad "15" smd rect
			(at 0 11.8999 90)
			(size 1.8034 0.508)
			(layers "F.Cu" "F.Mask" "F.Paste")
			(net "GND")
		)
		(pad "16" smd rect
			(at 0 12.750038 90)
			(size 1.8034 0.508)
			(layers "F.Cu" "F.Mask" "F.Paste")
			(net "M_L_DQ<9>")
		)
		(pad "17" smd rect
			(at 0 13.599922 90)
			(size 1.8034 0.508)
			(layers "F.Cu" "F.Mask" "F.Paste")
			(net "GND")
		)
		(pad "18" smd rect
			(at 0 14.45006 90)
			(size 1.8034 0.508)
			(layers "F.Cu" "F.Mask" "F.Paste")
			(net "M_L_DQS_DP<10>")
		)
		(pad "19" smd rect
			(at 0 15.299944 90)
			(size 1.8034 0.508)
			(layers "F.Cu" "F.Mask" "F.Paste")
			(net "M_L_DQS_DN<10>")
		)
		(pad "20" smd rect
			(at 0 16.150082 90)
			(size 1.8034 0.508)
			(layers "F.Cu" "F.Mask" "F.Paste")
			(net "GND")
		)
		(pad "21" smd rect
			(at 0 16.999966 90)
			(size 1.8034 0.508)
			(layers "F.Cu" "F.Mask" "F.Paste")
			(net "M_L_DQ<15>")
		)
		(pad "22" smd rect
			(at 0 17.850104 90)
			(size 1.8034 0.508)
			(layers "F.Cu" "F.Mask" "F.Paste")
			(net "GND")
		)
		(pad "23" smd rect
			(at 0 18.699988 90)
			(size 1.8034 0.508)
			(layers "F.Cu" "F.Mask" "F.Paste")
			(net "M_L_DQ<11>")
		)
		(pad "24" smd rect
			(at 0 19.550126 90)
			(size 1.8034 0.508)
			(layers "F.Cu" "F.Mask" "F.Paste")
			(net "GND")
		)
		(pad "25" smd rect
			(at 0 20.40001 90)
			(size 1.8034 0.508)
			(layers "F.Cu" "F.Mask" "F.Paste")
			(net "M_L_DQ<21>")
		)
		(pad "26" smd rect
			(at 0 21.249894 90)
			(size 1.8034 0.508)
			(layers "F.Cu" "F.Mask" "F.Paste")
			(net "GND")
		)
		(pad "27" smd rect
			(at 0 22.100032 90)
			(size 1.8034 0.508)
			(layers "F.Cu" "F.Mask" "F.Paste")
			(net "M_L_DQ<17>")
		)
		(pad "28" smd rect
			(at 0 22.949916 90)
			(size 1.8034 0.508)
			(layers "F.Cu" "F.Mask" "F.Paste")
			(net "GND")
		)
		(pad "29" smd rect
			(at 0 23.800054 90)
			(size 1.8034 0.508)
			(layers "F.Cu" "F.Mask" "F.Paste")
			(net "M_L_DQS_DP<11>")
		)
		(pad "30" smd rect
			(at 0 24.649938 90)
			(size 1.8034 0.508)
			(layers "F.Cu" "F.Mask" "F.Paste")
			(net "M_L_DQS_DN<11>")
		)
		(pad "31" smd rect
			(at 0 25.500076 90)
			(size 1.8034 0.508)
			(layers "F.Cu" "F.Mask" "F.Paste")
			(net "GND")
		)
		(pad "32" smd rect
			(at 0 26.34996 90)
			(size 1.8034 0.508)
			(layers "F.Cu" "F.Mask" "F.Paste")
			(net "M_L_DQ<23>")
		)
		(pad "33" smd rect
			(at 0 27.200098 90)
			(size 1.8034 0.508)
			(layers "F.Cu" "F.Mask" "F.Paste")
			(net "GND")
		)
		(pad "34" smd rect
			(at 0 28.049982 90)
			(size 1.8034 0.508)
			(layers "F.Cu" "F.Mask" "F.Paste")
			(net "M_L_DQ<19>")
		)
		(pad "35" smd rect
			(at 0 28.90012 90)
			(size 1.8034 0.508)
			(layers "F.Cu" "F.Mask" "F.Paste")
			(net "GND")
		)
		(pad "36" smd rect
			(at 0 29.750004 90)
			(size 1.8034 0.508)
			(layers "F.Cu" "F.Mask" "F.Paste")
			(net "M_L_DQ<29>")
		)
		(pad "37" smd rect
			(at 0 30.599888 90)
			(size 1.8034 0.508)
			(layers "F.Cu" "F.Mask" "F.Paste")
			(net "GND")
		)
		(pad "38" smd rect
			(at 0 31.450026 90)
			(size 1.8034 0.508)
			(layers "F.Cu" "F.Mask" "F.Paste")
			(net "M_L_DQ<25>")
		)
		(pad "39" smd rect
			(at 0 32.29991 90)
			(size 1.8034 0.508)
			(layers "F.Cu" "F.Mask" "F.Paste")
			(net "GND")
		)
		(pad "40" smd rect
			(at 0 33.150048 90)
			(size 1.8034 0.508)
			(layers "F.Cu" "F.Mask" "F.Paste")
			(net "M_L_DQS_DP<12>")
		)
		(pad "41" smd rect
			(at 0 33.999932 90)
			(size 1.8034 0.508)
			(layers "F.Cu" "F.Mask" "F.Paste")
			(net "M_L_DQS_DN<12>")
		)
		(pad "42" smd rect
			(at 0 34.85007 90)
			(size 1.8034 0.508)
			(layers "F.Cu" "F.Mask" "F.Paste")
			(net "GND")
		)
		(pad "43" smd rect
			(at 0 35.699954 90)
			(size 1.8034 0.508)
			(layers "F.Cu" "F.Mask" "F.Paste")
			(net "M_L_DQ<31>")
		)
		(pad "44" smd rect
			(at 0 36.550092 90)
			(size 1.8034 0.508)
			(layers "F.Cu" "F.Mask" "F.Paste")
			(net "GND")
		)
		(pad "45" smd rect
			(at 0 37.399976 90)
			(size 1.8034 0.508)
			(layers "F.Cu" "F.Mask" "F.Paste")
			(net "M_L_DQ<27>")
		)
		(pad "46" smd rect
			(at 0 38.250114 90)
			(size 1.8034 0.508)
			(layers "F.Cu" "F.Mask" "F.Paste")
			(net "GND")
		)
		(pad "47" smd rect
			(at 0 39.099998 90)
			(size 1.8034 0.508)
			(layers "F.Cu" "F.Mask" "F.Paste")
			(net "M_L_ECC<5>")
		)
		(pad "48" smd rect
			(at 0 39.949882 90)
			(size 1.8034 0.508)
			(layers "F.Cu" "F.Mask" "F.Paste")
			(net "GND")
		)
		(pad "49" smd rect
			(at 0 40.80002 90)
			(size 1.8034 0.508)
			(layers "F.Cu" "F.Mask" "F.Paste")
			(net "M_L_ECC<1>")
		)
		(pad "50" smd rect
			(at 0 41.649904 90)
			(size 1.8034 0.508)
			(layers "F.Cu" "F.Mask" "F.Paste")
			(net "GND")
		)
		(pad "51" smd rect
			(at 0 42.500042 90)
			(size 1.8034 0.508)
			(layers "F.Cu" "F.Mask" "F.Paste")
			(net "M_L_DQS_DP<17>")
		)
		(pad "52" smd rect
			(at 0 43.349926 90)
			(size 1.8034 0.508)
			(layers "F.Cu" "F.Mask" "F.Paste")
			(net "M_L_DQS_DN<17>")
		)
		(pad "53" smd rect
			(at 0 44.200064 90)
			(size 1.8034 0.508)
			(layers "F.Cu" "F.Mask" "F.Paste")
			(net "GND")
		)
		(pad "54" smd rect
			(at 0 45.049948 90)
			(size 1.8034 0.508)
			(layers "F.Cu" "F.Mask" "F.Paste")
			(net "M_L_ECC<7>")
		)
		(pad "55" smd rect
			(at 0 45.900086 90)
			(size 1.8034 0.508)
			(layers "F.Cu" "F.Mask" "F.Paste")
			(net "GND")
		)
		(pad "56" smd rect
			(at 0 46.74997 90)
			(size 1.8034 0.508)
			(layers "F.Cu" "F.Mask" "F.Paste")
			(net "M_L_ECC<3>")
		)
		(pad "57" smd rect
			(at 0 47.600108 90)
			(size 1.8034 0.508)
			(layers "F.Cu" "F.Mask" "F.Paste")
			(net "GND")
		)
		(pad "58" smd rect
			(at 0 48.449992 90)
			(size 1.8034 0.508)
			(layers "F.Cu" "F.Mask" "F.Paste")
			(net "M_KLM_RST_N")
		)
		(pad "59" smd rect
			(at 0 49.299876 90)
			(size 1.8034 0.508)
			(layers "F.Cu" "F.Mask" "F.Paste")
			(net "PVDDQ_KLM")
		)
		(pad "60" smd rect
			(at 0 50.150014 90)
			(size 1.8034 0.508)
			(layers "F.Cu" "F.Mask" "F.Paste")
			(net "M_L_CKE<0>")
		)
		(pad "61" smd rect
			(at 0 50.999898 90)
			(size 1.8034 0.508)
			(layers "F.Cu" "F.Mask" "F.Paste")
			(net "PVDDQ_KLM")
		)
		(pad "62" smd rect
			(at 0 51.850036 90)
			(size 1.8034 0.508)
			(layers "F.Cu" "F.Mask" "F.Paste")
			(net "M_L_ACT_N")
		)
		(pad "63" smd rect
			(at 0 52.69992 90)
			(size 1.8034 0.508)
			(layers "F.Cu" "F.Mask" "F.Paste")
			(net "M_L_BG<0>")
		)
		(pad "64" smd rect
			(at 0 53.550058 90)
			(size 1.8034 0.508)
			(layers "F.Cu" "F.Mask" "F.Paste")
			(net "PVDDQ_KLM")
		)
		(pad "65" smd rect
			(at 0 54.399942 90)
			(size 1.8034 0.508)
			(layers "F.Cu" "F.Mask" "F.Paste")
			(net "M_L_MA<12>")
		)
		(pad "66" smd rect
			(at 0 55.25008 90)
			(size 1.8034 0.508)
			(layers "F.Cu" "F.Mask" "F.Paste")
			(net "M_L_MA<9>")
		)
		(pad "67" smd rect
			(at 0 56.099964 90)
			(size 1.8034 0.508)
			(layers "F.Cu" "F.Mask" "F.Paste")
			(net "PVDDQ_KLM")
		)
		(pad "68" smd rect
			(at 0 56.950102 90)
			(size 1.8034 0.508)
			(layers "F.Cu" "F.Mask" "F.Paste")
			(net "M_L_MA<8>")
		)
		(pad "69" smd rect
			(at 0 57.799986 90)
			(size 1.8034 0.508)
			(layers "F.Cu" "F.Mask" "F.Paste")
			(net "M_L_MA<6>")
		)
		(pad "70" smd rect
			(at 0 58.650124 90)
			(size 1.8034 0.508)
			(layers "F.Cu" "F.Mask" "F.Paste")
			(net "PVDDQ_KLM")
		)
		(pad "71" smd rect
			(at 0 59.500008 90)
			(size 1.8034 0.508)
			(layers "F.Cu" "F.Mask" "F.Paste")
			(net "M_L_MA<3>")
		)
		(pad "72" smd rect
			(at 0 60.349892 90)
			(size 1.8034 0.508)
			(layers "F.Cu" "F.Mask" "F.Paste")
			(net "M_L_MA<1>")
		)
		(pad "73" smd rect
			(at 0 61.20003 90)
			(size 1.8034 0.508)
			(layers "F.Cu" "F.Mask" "F.Paste")
			(net "PVDDQ_KLM")
		)
		(pad "74" smd rect
			(at 0 62.049914 90)
			(size 1.8034 0.508)
			(layers "F.Cu" "F.Mask" "F.Paste")
			(net "M_L_CLK_DP<0>")
		)
		(pad "75" smd rect
			(at 0 62.900052 90)
			(size 1.8034 0.508)
			(layers "F.Cu" "F.Mask" "F.Paste")
			(net "M_L_CLK_DN<0>")
		)
		(pad "76" smd rect
			(at 0 63.749936 90)
			(size 1.8034 0.508)
			(layers "F.Cu" "F.Mask" "F.Paste")
			(net "PVDDQ_KLM")
		)
		(pad "77" smd rect
			(at 0 64.600074 90)
			(size 1.8034 0.508)
			(layers "F.Cu" "F.Mask" "F.Paste")
			(net "PVTT_KLM")
		)
		(pad "78" smd rect
			(at 0 70.550024 90)
			(size 1.8034 0.508)
			(layers "F.Cu" "F.Mask" "F.Paste")
			(net "FM_DIMM_EVENT_COD_N")
		)
		(pad "79" smd rect
			(at 0 71.399908 90)
			(size 1.8034 0.508)
			(layers "F.Cu" "F.Mask" "F.Paste")
			(net "M_L_MA<0>")
		)
		(pad "80" smd rect
			(at 0 72.250046 90)
			(size 1.8034 0.508)
			(layers "F.Cu" "F.Mask" "F.Paste")
			(net "PVDDQ_KLM")
		)
		(pad "81" smd rect
			(at 0 73.09993 90)
			(size 1.8034 0.508)
			(layers "F.Cu" "F.Mask" "F.Paste")
			(net "M_L_BA<0>")
		)
		(pad "82" smd rect
			(at 0 73.950068 90)
			(size 1.8034 0.508)
			(layers "F.Cu" "F.Mask" "F.Paste")
			(net "M_L_MA<16>")
		)
		(pad "83" smd rect
			(at 0 74.799952 90)
			(size 1.8034 0.508)
			(layers "F.Cu" "F.Mask" "F.Paste")
			(net "PVDDQ_KLM")
		)
		(pad "84" smd rect
			(at 0 75.65009 90)
			(size 1.8034 0.508)
			(layers "F.Cu" "F.Mask" "F.Paste")
			(net "M_L_CS_N<0>")
		)
		(pad "85" smd rect
			(at 0 76.499974 90)
			(size 1.8034 0.508)
			(layers "F.Cu" "F.Mask" "F.Paste")
			(net "PVDDQ_KLM")
		)
		(pad "86" smd rect
			(at 0 77.350112 90)
			(size 1.8034 0.508)
			(layers "F.Cu" "F.Mask" "F.Paste")
			(net "M_L_MA<15>")
		)
		(pad "87" smd rect
			(at 0 78.199996 90)
			(size 1.8034 0.508)
			(layers "F.Cu" "F.Mask" "F.Paste")
			(net "M_L_ODT<0>")
		)
		(pad "88" smd rect
			(at 0 79.04988 90)
			(size 1.8034 0.508)
			(layers "F.Cu" "F.Mask" "F.Paste")
			(net "PVDDQ_KLM")
		)
		(pad "89" smd rect
			(at 0 79.900018 90)
			(size 1.8034 0.508)
			(layers "F.Cu" "F.Mask" "F.Paste")
			(net "M_L_CS_N<1>")
		)
		(pad "90" smd rect
			(at 0 80.749902 90)
			(size 1.8034 0.508)
			(layers "F.Cu" "F.Mask" "F.Paste")
			(net "PVDDQ_KLM")
		)
		(pad "91" smd rect
			(at 0 81.60004 90)
			(size 1.8034 0.508)
			(layers "F.Cu" "F.Mask" "F.Paste")
			(net "M_L_ODT<1>")
		)
		(pad "92" smd rect
			(at 0 82.449924 90)
			(size 1.8034 0.508)
			(layers "F.Cu" "F.Mask" "F.Paste")
			(net "PVDDQ_KLM")
		)
		(pad "93" smd rect
			(at 0 83.300062 90)
			(size 1.8034 0.508)
			(layers "F.Cu" "F.Mask" "F.Paste")
			(net "M_L_CS_N<2>")
		)
		(pad "94" smd rect
			(at 0 84.149946 90)
			(size 1.8034 0.508)
			(layers "F.Cu" "F.Mask" "F.Paste")
			(net "GND")
		)
		(pad "95" smd rect
			(at 0 85.000084 90)
			(size 1.8034 0.508)
			(layers "F.Cu" "F.Mask" "F.Paste")
			(net "M_L_DQ<37>")
		)
		(pad "96" smd rect
			(at 0 85.849968 90)
			(size 1.8034 0.508)
			(layers "F.Cu" "F.Mask" "F.Paste")
			(net "GND")
		)
		(pad "97" smd rect
			(at 0 86.700106 90)
			(size 1.8034 0.508)
			(layers "F.Cu" "F.Mask" "F.Paste")
			(net "M_L_DQ<33>")
		)
		(pad "98" smd rect
			(at 0 87.54999 90)
			(size 1.8034 0.508)
			(layers "F.Cu" "F.Mask" "F.Paste")
			(net "GND")
		)
		(pad "99" smd rect
			(at 0 88.399874 90)
			(size 1.8034 0.508)
			(layers "F.Cu" "F.Mask" "F.Paste")
			(net "M_L_DQS_DP<13>")
		)
		(pad "100" smd rect
			(at 0 89.250012 90)
			(size 1.8034 0.508)
			(layers "F.Cu" "F.Mask" "F.Paste")
			(net "M_L_DQS_DN<13>")
		)
		(pad "101" smd rect
			(at 0 90.099896 90)
			(size 1.8034 0.508)
			(layers "F.Cu" "F.Mask" "F.Paste")
			(net "GND")
		)
		(pad "102" smd rect
			(at 0 90.950034 90)
			(size 1.8034 0.508)
			(layers "F.Cu" "F.Mask" "F.Paste")
			(net "M_L_DQ<39>")
		)
		(pad "103" smd rect
			(at 0 91.799918 90)
			(size 1.8034 0.508)
			(layers "F.Cu" "F.Mask" "F.Paste")
			(net "GND")
		)
		(pad "104" smd rect
			(at 0 92.650056 90)
			(size 1.8034 0.508)
			(layers "F.Cu" "F.Mask" "F.Paste")
			(net "M_L_DQ<35>")
		)
		(pad "105" smd rect
			(at 0 93.49994 90)
			(size 1.8034 0.508)
			(layers "F.Cu" "F.Mask" "F.Paste")
			(net "GND")
		)
		(pad "106" smd rect
			(at 0 94.350078 90)
			(size 1.8034 0.508)
			(layers "F.Cu" "F.Mask" "F.Paste")
			(net "M_L_DQ<45>")
		)
		(pad "107" smd rect
			(at 0 95.199962 90)
			(size 1.8034 0.508)
			(layers "F.Cu" "F.Mask" "F.Paste")
			(net "GND")
		)
		(pad "108" smd rect
			(at 0 96.0501 90)
			(size 1.8034 0.508)
			(layers "F.Cu" "F.Mask" "F.Paste")
			(net "M_L_DQ<41>")
		)
		(pad "109" smd rect
			(at 0 96.899984 90)
			(size 1.8034 0.508)
			(layers "F.Cu" "F.Mask" "F.Paste")
			(net "GND")
		)
		(pad "110" smd rect
			(at 0 97.750122 90)
			(size 1.8034 0.508)
			(layers "F.Cu" "F.Mask" "F.Paste")
			(net "M_L_DQS_DP<14>")
		)
		(pad "111" smd rect
			(at 0 98.600006 90)
			(size 1.8034 0.508)
			(layers "F.Cu" "F.Mask" "F.Paste")
			(net "M_L_DQS_DN<14>")
		)
		(pad "112" smd rect
			(at 0 99.44989 90)
			(size 1.8034 0.508)
			(layers "F.Cu" "F.Mask" "F.Paste")
			(net "GND")
		)
		(pad "113" smd rect
			(at 0 100.300028 90)
			(size 1.8034 0.508)
			(layers "F.Cu" "F.Mask" "F.Paste")
			(net "M_L_DQ<47>")
		)
		(pad "114" smd rect
			(at 0 101.149912 90)
			(size 1.8034 0.508)
			(layers "F.Cu" "F.Mask" "F.Paste")
			(net "GND")
		)
		(pad "115" smd rect
			(at 0 102.00005 90)
			(size 1.8034 0.508)
			(layers "F.Cu" "F.Mask" "F.Paste")
			(net "M_L_DQ<43>")
		)
		(pad "116" smd rect
			(at 0 102.849934 90)
			(size 1.8034 0.508)
			(layers "F.Cu" "F.Mask" "F.Paste")
			(net "GND")
		)
		(pad "117" smd rect
			(at 0 103.700072 90)
			(size 1.8034 0.508)
			(layers "F.Cu" "F.Mask" "F.Paste")
			(net "M_L_DQ<53>")
		)
		(pad "118" smd rect
			(at 0 104.549956 90)
			(size 1.8034 0.508)
			(layers "F.Cu" "F.Mask" "F.Paste")
			(net "GND")
		)
		(pad "119" smd rect
			(at 0 105.400094 90)
			(size 1.8034 0.508)
			(layers "F.Cu" "F.Mask" "F.Paste")
			(net "M_L_DQ<49>")
		)
		(pad "120" smd rect
			(at 0 106.249978 90)
			(size 1.8034 0.508)
			(layers "F.Cu" "F.Mask" "F.Paste")
			(net "GND")
		)
	)
)
